# BASEBOARD_FAB2 (Tioga Pass) — schematic netlist excerpt (pin names and nets, part order shuffled) for the footprints in the layout excerpt that follows; sources: Cadence DE-HDL packaged netlist, KiCad conversion of Wiwynn_Tioga_Pass_MB.brd

CR1L2  DIODE  1N4148W IC  pkg SM  page 168 : C = FM_DB_UART_SEL2_N ; A = FM_DB_UART_SEL1_N
C1C3  SC1U10V2KX-4-GP  10%  pkg SMD-BCG6  page 210 : \1\ = P5V_STBY ; \2\ = GND
R8W6  RES  1.37K 1% CHIP  pkg 0402  page 138 : A = P3V3_STBY ; B = SMB_VR_STBY_LVC3_SDA_R1

(kicad_pcb
	(version 20260206)
	(generator "pcbnew")
	(generator_version "10.0")
	(general
		(thickness 1.6)
		(legacy_teardrops no)
	)
	(paper "A4")
	(title_block
		(title "Wiwynn_Tioga_Pass_MB.brd")
		(comment 1 "Tioga Pass / footprints 4151-4153 of 4770")
	)
	(layers
		(0 "F.Cu" signal "TOP")
		(4 "In1.Cu" signal "L2GND")
		(6 "In2.Cu" signal "L3")
		(8 "In3.Cu" signal "L4GND")
		(10 "In4.Cu" signal "L5")
		(12 "In5.Cu" signal "L6GND")
		(14 "In6.Cu" signal "L7VCC")
		(16 "In7.Cu" signal "L8VCC")
		(18 "In8.Cu" signal "L9GND")
		(20 "In9.Cu" signal "L10")
		(22 "In10.Cu" signal "L11GND")
		(24 "In11.Cu" signal "L12")
		(26 "In12.Cu" signal "L13GND")
		(2 "B.Cu" signal "BOTTOM")
		(9 "F.Adhes" user "F.Adhesive")
		(11 "B.Adhes" user "B.Adhesive")
		(13 "F.Paste" user "Package Geometry/Pastemask Top")
		(15 "B.Paste" user "Package Geometry/Pastemask Bottom")
		(5 "F.SilkS" user "Ref Des/Silkscreen Top")
		(7 "B.SilkS" user "Ref Des/Silkscreen Bottom")
		(1 "F.Mask" user "Board Geometry/Soldermask Top")
		(3 "B.Mask" user "Board Geometry/Soldermask Bottom")
		(17 "Dwgs.User" user "User.Drawings")
		(19 "Cmts.User" user "User.Comments")
		(21 "Eco1.User" user "User.Eco1")
		(23 "Eco2.User" user "User.Eco2")
		(25 "Edge.Cuts" user "Board Geometry/Outline")
		(27 "Margin" user)
		(31 "F.CrtYd" user "Package Geometry/Place Bound Top")
		(29 "B.CrtYd" user "Package Geometry/Place Bound Bottom")
		(35 "F.Fab" user "Ref Des/Assembly Top")
		(33 "B.Fab" user "Ref Des/Assembly Bottom")
	)
	(footprint ""
		(layer "B.Cu")
		(at 399.2372 -87.4522 180)
		(property "Reference" "R8W6"
			(at 0.8382 -0.67818 180)
			(unlocked yes)
			(layer "B.SilkS")
			(effects
				(font
					(size 0.4064 0.254)
					(thickness 0.1524)
				)
				(justify left mirror)
			)
		)
		(property "Value" ""
			(at 0 0 0)
			(layer "B.Fab")
			(effects
				(font
					(size 1.27 1.27)
				)
				(justify mirror)
			)
		)
		(duplicate_pad_numbers_are_jumpers no)
		(fp_poly
			(pts
				(xy 0.2794 -0.1016) (xy -0.2794 -0.1016) (xy -0.2794 0.9906) (xy 0.2794 0.9906)
			)
			(stroke
				(width 0)
				(type default)
			)
			(fill no)
			(layer "B.CrtYd")
		)
		(fp_line
			(start 0.2794 0.9906)
			(end -0.2794 0.9906)
			(stroke
				(width 0.1)
				(type default)
			)
			(layer "B.Fab")
		)
		(fp_line
			(start 0.2794 -0.1016)
			(end 0.2794 0.9906)
			(stroke
				(width 0.1)
				(type default)
			)
			(layer "B.Fab")
		)
		(fp_line
			(start -0.2794 0.9906)
			(end -0.2794 -0.1016)
			(stroke
				(width 0.1)
				(type default)
			)
			(layer "B.Fab")
		)
		(fp_line
			(start -0.2794 -0.1016)
			(end 0.2794 -0.1016)
			(stroke
				(width 0.1)
				(type default)
			)
			(layer "B.Fab")
		)
		(pad "1" smd rect
			(at 0 0)
			(size 0.508 0.508)
			(layers "B.Cu" "B.Mask" "B.Paste")
			(net "P3V3_STBY")
		)
		(pad "2" smd rect
			(at 0 0.889)
			(size 0.508 0.508)
			(layers "B.Cu" "B.Mask" "B.Paste")
			(net "SMB_VR_STBY_LVC3_SDA_R1")
		)
		(zone
			(layer "B.Cu")
			(hatch none 0.5)
			(connect_pads
				(clearance 0)
			)
			(min_thickness 0.25)
			(keepout
				(tracks not_allowed)
				(vias allowed)
				(pads allowed)
				(copperpour not_allowed)
				(footprints allowed)
			)
			(placement
				(enabled no)
				(sheetname "")
			)
			(fill
				(thermal_gap 0.5)
				(thermal_bridge_width 0.5)
				(island_removal_mode 0)
			)
			(polygon
				(pts
					(xy 398.9832 -88.0872) (xy 399.4912 -88.0872) (xy 399.4912 -87.7062) (xy 398.9832 -87.7062)
				)
			)
		)
		(zone
			(layer "B.Cu")
			(hatch none 0.5)
			(connect_pads
				(clearance 0)
			)
			(min_thickness 0.25)
			(keepout
				(tracks allowed)
				(vias not_allowed)
				(pads allowed)
				(copperpour not_allowed)
				(footprints allowed)
			)
			(placement
				(enabled no)
				(sheetname "")
			)
			(fill
				(thermal_gap 0.5)
				(thermal_bridge_width 0.5)
				(island_removal_mode 0)
			)
			(polygon
				(pts
					(xy 398.9832 -87.7062) (xy 399.4912 -87.7062) (xy 399.4912 -88.0872) (xy 398.9832 -88.0872)
				)
			)
		)
	)
	(footprint ""
		(layer "B.Cu")
		(at 33.689036 -93.818202 90)
		(property "Reference" "C1C3"
			(at 0 0 90)
			(layer "B.SilkS")
			(hide yes)
			(effects
				(font
					(size 1.27 1.27)
				)
				(justify mirror)
			)
		)
		(property "Value" "*"
			(at -1.1811 -2.8194 90)
			(unlocked yes)
			(layer "B.Fab")
			(hide yes)
			(effects
				(font
					(size 1.27 1.016)
					(thickness 0.1524)
				)
				(justify mirror)
			)
		)
		(property "Device Type" "SC1U10V2KX-4-GP_SMD-BCG6-SC1U1A"
			(at -1.1811 -4.3434 90)
			(unlocked yes)
			(layer "B.Fab")
			(hide yes)
			(effects
				(font
					(size 1.27 1.016)
					(thickness 0.1524)
				)
				(justify mirror)
			)
		)
		(duplicate_pad_numbers_are_jumpers no)
		(fp_rect
			(start 0.4318 0.9525)
			(end -0.4318 -0.9525)
			(stroke
				(width 0)
				(type default)
			)
			(fill no)
			(layer "B.CrtYd")
		)
		(fp_rect
			(start 0.4318 0.9525)
			(end -0.4318 -0.9525)
			(stroke
				(width 0)
				(type default)
			)
			(fill no)
			(layer "B.Fab")
		)
		(pad "1" smd custom
			(at 0 -0.4445 270)
			(size 0.1524 0.1524)
			(layers "B.Cu" "B.Mask" "B.Paste")
			(net "P5V_STBY")
			(options
				(clearance outline)
				(anchor circle)
			)
			(primitives
				(gr_poly
					(pts
						(arc
							(start 0.3048 0.2032)
							(mid 0.275042 0.275042)
							(end 0.2032 0.3048)
						)
						(arc
							(start -0.2032 0.3048)
							(mid -0.275042 0.275042)
							(end -0.3048 0.2032)
						)
						(arc
							(start -0.3048 -0.2032)
							(mid -0.275042 -0.275042)
							(end -0.2032 -0.3048)
						)
						(arc
							(start 0.2032 -0.3048)
							(mid 0.275042 -0.275042)
							(end 0.3048 -0.2032)
						)
					)
					(width 0)
					(fill yes)
				)
			)
		)
		(pad "2" smd custom
			(at 0 0.4445 270)
			(size 0.1524 0.1524)
			(layers "B.Cu" "B.Mask" "B.Paste")
			(net "GND")
			(options
				(clearance outline)
				(anchor circle)
			)
			(primitives
				(gr_poly
					(pts
						(arc
							(start 0.3048 0.2032)
							(mid 0.275042 0.275042)
							(end 0.2032 0.3048)
						)
						(arc
							(start -0.2032 0.3048)
							(mid -0.275042 0.275042)
							(end -0.3048 0.2032)
						)
						(arc
							(start -0.3048 -0.2032)
							(mid -0.275042 -0.275042)
							(end -0.2032 -0.3048)
						)
						(arc
							(start 0.2032 -0.3048)
							(mid 0.275042 -0.275042)
							(end 0.3048 -0.2032)
						)
					)
					(width 0)
					(fill yes)
				)
			)
		)
	)
	(footprint ""
		(layer "B.Cu")
		(at 484.124 -147.828 90)
		(property "Reference" "CR1L2"
			(at 0 0 90)
			(layer "B.SilkS")
			(hide yes)
			(effects
				(font
					(size 1.27 1.27)
				)
				(justify mirror)
			)
		)
		(property "Value" ""
			(at 0 0 90)
			(layer "B.Fab")
			(effects
				(font
					(size 1.27 1.27)
				)
				(justify mirror)
			)
		)
		(duplicate_pad_numbers_are_jumpers no)
		(fp_line
			(start 0.9144 0.1016)
			(end 0.9144 2.9464)
			(stroke
				(width 0.1524)
				(type default)
			)
			(layer "B.SilkS")
		)
		(fp_line
			(start 0.8382 0.1016)
			(end 0.9144 0.1016)
			(stroke
				(width 0.1524)
				(type default)
			)
			(layer "B.SilkS")
		)
		(fp_line
			(start -0.8382 0.1016)
			(end -0.9144 0.1016)
			(stroke
				(width 0.1524)
				(type default)
			)
			(layer "B.SilkS")
		)
		(fp_line
			(start -0.9144 0.1016)
			(end -0.9144 2.9464)
			(stroke
				(width 0.1524)
				(type default)
			)
			(layer "B.SilkS")
		)
		(fp_line
			(start 0.9144 2.9464)
			(end 0.8382 2.9464)
			(stroke
				(width 0.1524)
				(type default)
			)
			(layer "B.SilkS")
		)
		(fp_line
			(start -0.9144 2.9464)
			(end -0.8382 2.9464)
			(stroke
				(width 0.1524)
				(type default)
			)
			(layer "B.SilkS")
		)
		(fp_circle
			(center -1.128776 -0.907288)
			(end -1.128776 -0.780288)
			(stroke
				(width 0.254)
				(type default)
			)
			(fill no)
			(layer "B.SilkS")
		)
		(fp_poly
			(pts
				(xy 0 0.1016) (xy -0.5334 0.1016) (xy -0.7366 0.1016) (xy -0.9144 0.1016) (xy -0.9144 2.9464) (xy -0.8382 2.9464)
				(xy -0.762 2.9464) (xy 0.9144 2.9464) (xy 0.9144 2.7686) (xy 0.9144 2.159) (xy 0.9144 0.1016) (xy 0.7366 0.1016)
				(xy 0.5842 0.1016)
			)
			(stroke
				(width 0)
				(type default)
			)
			(fill no)
			(layer "B.CrtYd")
		)
		(fp_line
			(start 0.9144 0.1016)
			(end 0.9144 2.9464)
			(stroke
				(width 0.1)
				(type default)
			)
			(layer "B.Fab")
		)
		(fp_line
			(start -0.9144 0.1016)
			(end 0.9144 0.1016)
			(stroke
				(width 0.1)
				(type default)
			)
			(layer "B.Fab")
		)
		(fp_line
			(start 0.9144 2.9464)
			(end -0.9144 2.9464)
			(stroke
				(width 0.1)
				(type default)
			)
			(layer "B.Fab")
		)
		(fp_line
			(start -0.9144 2.9464)
			(end -0.9144 0.1016)
			(stroke
				(width 0.1)
				(type default)
			)
			(layer "B.Fab")
		)
		(fp_circle
			(center -1.128776 -0.907288)
			(end -1.128776 -0.780288)
			(stroke
				(width 0.254)
				(type default)
			)
			(fill no)
			(layer "B.Fab")
		)
		(pad "1" smd rect
			(at 0 0)
			(size 1.524 0.762)
			(layers "B.Cu" "B.Mask" "B.Paste")
			(net "FM_DB_UART_SEL2_N")
		)
		(pad "2" smd rect
			(at 0 3.048 180)
			(size 1.524 0.762)
			(layers "B.Cu" "B.Mask" "B.Paste")
			(net "FM_DB_UART_SEL1_N")
		)
	)
)
